(kicad_pcb
	(version 20260206)
	(generator "pcbnew")
	(generator_version "10.0")
	(general
		(thickness 1.6)
		(legacy_teardrops no)
	)
	(paper "A4")
	(title_block
		(title "04192023_DAF0TMB3IC0_F0TG_MB_C_brd_V02_OCP.brd")
		(comment 1 "Grand Teton / footprints 2195-2201 of 8354")
	)
	(layers
		(0 "F.Cu" signal "TOP")
		(4 "In1.Cu" signal "GND")
		(6 "In2.Cu" signal "IN1")
		(8 "In3.Cu" signal "GND1")
		(10 "In4.Cu" signal "IN2")
		(12 "In5.Cu" signal "GND2")
		(14 "In6.Cu" signal "IN3")
		(16 "In7.Cu" signal "GND3")
		(18 "In8.Cu" signal "VCC")
		(20 "In9.Cu" signal "VCC1")
		(22 "In10.Cu" signal "GND4")
		(24 "In11.Cu" signal "IN4")
		(26 "In12.Cu" signal "GND5")
		(28 "In13.Cu" signal "IN5")
		(30 "In14.Cu" signal "GND6")
		(32 "In15.Cu" signal "IN6")
		(34 "In16.Cu" signal "GND7")
		(2 "B.Cu" signal "BOTTOM")
		(9 "F.Adhes" user "F.Adhesive")
		(11 "B.Adhes" user "B.Adhesive")
		(13 "F.Paste" user "Package Geometry/Pastemask Top")
		(15 "B.Paste" user "Package Geometry/Pastemask Bottom")
		(5 "F.SilkS" user "Ref Des/Silkscreen Top")
		(7 "B.SilkS" user "Ref Des/Silkscreen Bottom")
		(1 "F.Mask" user "Board Geometry/Soldermask Top")
		(3 "B.Mask" user "Board Geometry/Soldermask Bottom")
		(17 "Dwgs.User" user "User.Drawings")
		(19 "Cmts.User" user "User.Comments")
		(21 "Eco1.User" user "User.Eco1")
		(23 "Eco2.User" user "User.Eco2")
		(25 "Edge.Cuts" user "Board Geometry/Outline")
		(27 "Margin" user)
		(31 "F.CrtYd" user "Package Geometry/Place Bound Top")
		(29 "B.CrtYd" user "Package Geometry/Place Bound Bottom")
		(35 "F.Fab" user "Ref Des/Assembly Top")
		(33 "B.Fab" user "Ref Des/Assembly Bottom")
	)
	(footprint ""
		(layer "F.Cu")
		(at 21.81987 -385.91109 180)
		(property "Reference" "PC6641"
			(at 0 0 180)
			(layer "F.SilkS")
			(hide yes)
			(effects
				(font
					(size 1.27 1.27)
				)
			)
		)
		(property "Value" ""
			(at 0 0 180)
			(layer "F.Fab")
			(effects
				(font
					(size 1.27 1.27)
				)
			)
		)
		(duplicate_pad_numbers_are_jumpers no)
		(fp_line
			(start 0.7874 0.4064)
			(end -0.7874 0.4064)
			(stroke
				(width 0.1524)
				(type default)
			)
			(layer "F.SilkS")
		)
		(fp_line
			(start 0.7874 -0.4064)
			(end 0.7874 0.4064)
			(stroke
				(width 0.1524)
				(type default)
			)
			(layer "F.SilkS")
		)
		(fp_line
			(start -0.7874 0.4064)
			(end -0.7874 -0.4064)
			(stroke
				(width 0.1524)
				(type default)
			)
			(layer "F.SilkS")
		)
		(fp_line
			(start -0.7874 -0.4064)
			(end 0.7874 -0.4064)
			(stroke
				(width 0.1524)
				(type default)
			)
			(layer "F.SilkS")
		)
		(fp_line
			(start 0.67945 0.3048)
			(end 0.120396 0.3048)
			(stroke
				(width 0.1)
				(type default)
			)
			(layer "F.Fab")
		)
		(fp_line
			(start 0.67945 -0.3048)
			(end 0.67945 0.3048)
			(stroke
				(width 0.1)
				(type default)
			)
			(layer "F.Fab")
		)
		(fp_line
			(start 0.12065 -0.2794)
			(end 0.12065 -0.3048)
			(stroke
				(width 0.1)
				(type default)
			)
			(layer "F.Fab")
		)
		(fp_line
			(start 0.12065 -0.3048)
			(end 0.67945 -0.3048)
			(stroke
				(width 0.1)
				(type default)
			)
			(layer "F.Fab")
		)
		(fp_line
			(start 0.120396 0.3048)
			(end 0.120396 0.2794)
			(stroke
				(width 0.1)
				(type default)
			)
			(layer "F.Fab")
		)
		(fp_line
			(start 0.120396 0.2794)
			(end -0.12065 0.2794)
			(stroke
				(width 0.1)
				(type default)
			)
			(layer "F.Fab")
		)
		(fp_line
			(start -0.12065 0.3048)
			(end -0.67945 0.3048)
			(stroke
				(width 0.1)
				(type default)
			)
			(layer "F.Fab")
		)
		(fp_line
			(start -0.12065 0.2794)
			(end -0.12065 0.3048)
			(stroke
				(width 0.1)
				(type default)
			)
			(layer "F.Fab")
		)
		(fp_line
			(start -0.12065 -0.2794)
			(end 0.12065 -0.2794)
			(stroke
				(width 0.1)
				(type default)
			)
			(layer "F.Fab")
		)
		(fp_line
			(start -0.12065 -0.305054)
			(end -0.12065 -0.2794)
			(stroke
				(width 0.1)
				(type default)
			)
			(layer "F.Fab")
		)
		(fp_line
			(start -0.67945 0.3048)
			(end -0.67945 -0.305054)
			(stroke
				(width 0.1)
				(type default)
			)
			(layer "F.Fab")
		)
		(fp_line
			(start -0.67945 -0.305054)
			(end -0.12065 -0.305054)
			(stroke
				(width 0.1)
				(type default)
			)
			(layer "F.Fab")
		)
		(pad "1" smd circle
			(at -0.40005 0 180)
			(size 0 0)
			(layers "F.Cu" "F.Mask" "F.Paste")
			(net "SW_P0V9_RETIMER_CPU1_SW2")
		)
		(pad "2" smd circle
			(at 0.40005 0 180)
			(size 0 0)
			(layers "F.Cu" "F.Mask" "F.Paste")
			(net "SW_P0V9_RETIMER_CPU1_SW2_RC")
		)
	)
	(footprint ""
		(layer "F.Cu")
		(at 442.134752 -389.281416 90)
		(property "Reference" "PC6565"
			(at 0 0 90)
			(layer "F.SilkS")
			(hide yes)
			(effects
				(font
					(size 1.27 1.27)
				)
			)
		)
		(property "Value" ""
			(at 0 0 90)
			(layer "F.Fab")
			(effects
				(font
					(size 1.27 1.27)
				)
			)
		)
		(duplicate_pad_numbers_are_jumpers no)
		(fp_line
			(start 0.7874 -0.4064)
			(end 0.7874 0.4064)
			(stroke
				(width 0.1524)
				(type default)
			)
			(layer "F.SilkS")
		)
		(fp_line
			(start -0.7874 -0.4064)
			(end 0.7874 -0.4064)
			(stroke
				(width 0.1524)
				(type default)
			)
			(layer "F.SilkS")
		)
		(fp_line
			(start 0.7874 0.4064)
			(end -0.7874 0.4064)
			(stroke
				(width 0.1524)
				(type default)
			)
			(layer "F.SilkS")
		)
		(fp_line
			(start -0.7874 0.4064)
			(end -0.7874 -0.4064)
			(stroke
				(width 0.1524)
				(type default)
			)
			(layer "F.SilkS")
		)
		(fp_line
			(start -0.12065 -0.305054)
			(end -0.12065 -0.2794)
			(stroke
				(width 0.1)
				(type default)
			)
			(layer "F.Fab")
		)
		(fp_line
			(start -0.67945 -0.305054)
			(end -0.12065 -0.305054)
			(stroke
				(width 0.1)
				(type default)
			)
			(layer "F.Fab")
		)
		(fp_line
			(start 0.67945 -0.3048)
			(end 0.67945 0.3048)
			(stroke
				(width 0.1)
				(type default)
			)
			(layer "F.Fab")
		)
		(fp_line
			(start 0.12065 -0.3048)
			(end 0.67945 -0.3048)
			(stroke
				(width 0.1)
				(type default)
			)
			(layer "F.Fab")
		)
		(fp_line
			(start 0.12065 -0.2794)
			(end 0.12065 -0.3048)
			(stroke
				(width 0.1)
				(type default)
			)
			(layer "F.Fab")
		)
		(fp_line
			(start -0.12065 -0.2794)
			(end 0.12065 -0.2794)
			(stroke
				(width 0.1)
				(type default)
			)
			(layer "F.Fab")
		)
		(fp_line
			(start 0.120396 0.2794)
			(end -0.12065 0.2794)
			(stroke
				(width 0.1)
				(type default)
			)
			(layer "F.Fab")
		)
		(fp_line
			(start -0.12065 0.2794)
			(end -0.12065 0.3048)
			(stroke
				(width 0.1)
				(type default)
			)
			(layer "F.Fab")
		)
		(fp_line
			(start 0.67945 0.3048)
			(end 0.120396 0.3048)
			(stroke
				(width 0.1)
				(type default)
			)
			(layer "F.Fab")
		)
		(fp_line
			(start 0.120396 0.3048)
			(end 0.120396 0.2794)
			(stroke
				(width 0.1)
				(type default)
			)
			(layer "F.Fab")
		)
		(fp_line
			(start -0.12065 0.3048)
			(end -0.67945 0.3048)
			(stroke
				(width 0.1)
				(type default)
			)
			(layer "F.Fab")
		)
		(fp_line
			(start -0.67945 0.3048)
			(end -0.67945 -0.305054)
			(stroke
				(width 0.1)
				(type default)
			)
			(layer "F.Fab")
		)
		(pad "1" smd circle
			(at -0.40005 0 90)
			(size 0 0)
			(layers "F.Cu" "F.Mask" "F.Paste")
			(net "P0V9_CPU0_RT_2D")
		)
		(pad "2" smd circle
			(at 0.40005 0 90)
			(size 0 0)
			(layers "F.Cu" "F.Mask" "F.Paste")
			(net "GND")
		)
	)
	(footprint ""
		(layer "F.Cu")
		(at 221.28226 -98.11004 90)
		(property "Reference" "R1509"
			(at 0 0 90)
			(layer "F.SilkS")
			(hide yes)
			(effects
				(font
					(size 1.27 1.27)
				)
			)
		)
		(property "Value" ""
			(at 0 0 90)
			(layer "F.Fab")
			(effects
				(font
					(size 1.27 1.27)
				)
			)
		)
		(duplicate_pad_numbers_are_jumpers no)
		(fp_line
			(start 0.7874 -0.4064)
			(end 0.7874 0.4064)
			(stroke
				(width 0.1524)
				(type default)
			)
			(layer "F.SilkS")
		)
		(fp_line
			(start -0.7874 -0.4064)
			(end 0.7874 -0.4064)
			(stroke
				(width 0.1524)
				(type default)
			)
			(layer "F.SilkS")
		)
		(fp_line
			(start 0.7874 0.4064)
			(end -0.7874 0.4064)
			(stroke
				(width 0.1524)
				(type default)
			)
			(layer "F.SilkS")
		)
		(fp_line
			(start -0.7874 0.4064)
			(end -0.7874 -0.4064)
			(stroke
				(width 0.1524)
				(type default)
			)
			(layer "F.SilkS")
		)
		(fp_line
			(start -0.12065 -0.305054)
			(end -0.12065 -0.2794)
			(stroke
				(width 0.1)
				(type default)
			)
			(layer "F.Fab")
		)
		(fp_line
			(start -0.67945 -0.305054)
			(end -0.12065 -0.305054)
			(stroke
				(width 0.1)
				(type default)
			)
			(layer "F.Fab")
		)
		(fp_line
			(start 0.67945 -0.3048)
			(end 0.67945 0.3048)
			(stroke
				(width 0.1)
				(type default)
			)
			(layer "F.Fab")
		)
		(fp_line
			(start 0.12065 -0.3048)
			(end 0.67945 -0.3048)
			(stroke
				(width 0.1)
				(type default)
			)
			(layer "F.Fab")
		)
		(fp_line
			(start 0.12065 -0.2794)
			(end 0.12065 -0.3048)
			(stroke
				(width 0.1)
				(type default)
			)
			(layer "F.Fab")
		)
		(fp_line
			(start -0.12065 -0.2794)
			(end 0.12065 -0.2794)
			(stroke
				(width 0.1)
				(type default)
			)
			(layer "F.Fab")
		)
		(fp_line
			(start 0.120396 0.2794)
			(end -0.12065 0.2794)
			(stroke
				(width 0.1)
				(type default)
			)
			(layer "F.Fab")
		)
		(fp_line
			(start -0.12065 0.2794)
			(end -0.12065 0.3048)
			(stroke
				(width 0.1)
				(type default)
			)
			(layer "F.Fab")
		)
		(fp_line
			(start 0.67945 0.3048)
			(end 0.120396 0.3048)
			(stroke
				(width 0.1)
				(type default)
			)
			(layer "F.Fab")
		)
		(fp_line
			(start 0.120396 0.3048)
			(end 0.120396 0.2794)
			(stroke
				(width 0.1)
				(type default)
			)
			(layer "F.Fab")
		)
		(fp_line
			(start -0.12065 0.3048)
			(end -0.67945 0.3048)
			(stroke
				(width 0.1)
				(type default)
			)
			(layer "F.Fab")
		)
		(fp_line
			(start -0.67945 0.3048)
			(end -0.67945 -0.305054)
			(stroke
				(width 0.1)
				(type default)
			)
			(layer "F.Fab")
		)
		(pad "1" smd circle
			(at -0.40005 0 90)
			(size 0 0)
			(layers "F.Cu" "F.Mask" "F.Paste")
			(net "HP_LVC3_OCP_V3_1_P12V_PWRGD")
		)
		(pad "2" smd circle
			(at 0.40005 0 90)
			(size 0 0)
			(layers "F.Cu" "F.Mask" "F.Paste")
			(net "HP_LVC3_OCP_V3_1_P12V_R2_PWRGD")
		)
	)
	(footprint ""
		(layer "F.Cu")
		(at 346.653866 -416.899344 -90)
		(property "Reference" "C6530"
			(at 0 0 270)
			(layer "F.SilkS")
			(hide yes)
			(effects
				(font
					(size 1.27 1.27)
				)
			)
		)
		(property "Value" ""
			(at 0 0 270)
			(layer "F.Fab")
			(effects
				(font
					(size 1.27 1.27)
				)
			)
		)
		(duplicate_pad_numbers_are_jumpers no)
		(fp_line
			(start -0.299974 0.150114)
			(end -0.299974 -0.150114)
			(stroke
				(width 0.1)
				(type default)
			)
			(layer "F.Fab")
		)
		(fp_line
			(start 0.299974 0.150114)
			(end -0.299974 0.150114)
			(stroke
				(width 0.1)
				(type default)
			)
			(layer "F.Fab")
		)
		(fp_line
			(start -0.299974 -0.150114)
			(end 0.299974 -0.150114)
			(stroke
				(width 0.1)
				(type default)
			)
			(layer "F.Fab")
		)
		(fp_line
			(start 0.299974 -0.150114)
			(end 0.299974 0.150114)
			(stroke
				(width 0.1)
				(type default)
			)
			(layer "F.Fab")
		)
		(pad "1" smd rect
			(at -0.2667 0 270)
			(size 0.3048 0.381)
			(layers "F.Cu" "F.Mask" "F.Paste")
			(net "P5E_CPU0_P0_TX_BUF_C_DN<14>")
		)
		(pad "2" smd rect
			(at 0.2667 0 270)
			(size 0.3048 0.381)
			(layers "F.Cu" "F.Mask" "F.Paste")
			(net "P5E_CPU0_P0_TX_BUF_DN<14>")
		)
	)
	(footprint ""
		(layer "F.Cu")
		(at 169.1894 -333.375508)
		(property "Reference" "TP18"
			(at -2.305812 -5.26923 0)
			(unlocked yes)
			(layer "F.SilkS")
			(effects
				(font
					(size 0.7874 0.5842)
					(thickness 0.1524)
				)
				(justify left)
			)
		)
		(property "Value" ""
			(at 0 0 0)
			(layer "F.Fab")
			(effects
				(font
					(size 1.27 1.27)
				)
			)
		)
		(duplicate_pad_numbers_are_jumpers no)
		(pad "1" smd circle
			(at 0 0)
			(size 0.762 0.762)
			(layers "F.Cu" "F.Mask" "F.Paste")
			(net "VSENSE_PVDD11_S3_P1_DP")
		)
	)
	(footprint ""
		(layer "F.Cu")
		(at 178.689 -100.294948 90)
		(property "Reference" "R243"
			(at 0 0 90)
			(layer "F.SilkS")
			(hide yes)
			(effects
				(font
					(size 1.27 1.27)
				)
			)
		)
		(property "Value" ""
			(at 0 0 90)
			(layer "F.Fab")
			(effects
				(font
					(size 1.27 1.27)
				)
			)
		)
		(duplicate_pad_numbers_are_jumpers no)
		(fp_line
			(start 0.7874 -0.4064)
			(end 0.7874 0.4064)
			(stroke
				(width 0.1524)
				(type default)
			)
			(layer "F.SilkS")
		)
		(fp_line
			(start -0.7874 -0.4064)
			(end 0.7874 -0.4064)
			(stroke
				(width 0.1524)
				(type default)
			)
			(layer "F.SilkS")
		)
		(fp_line
			(start 0.7874 0.4064)
			(end -0.7874 0.4064)
			(stroke
				(width 0.1524)
				(type default)
			)
			(layer "F.SilkS")
		)
		(fp_line
			(start -0.7874 0.4064)
			(end -0.7874 -0.4064)
			(stroke
				(width 0.1524)
				(type default)
			)
			(layer "F.SilkS")
		)
		(fp_line
			(start -0.12065 -0.305054)
			(end -0.12065 -0.2794)
			(stroke
				(width 0.1)
				(type default)
			)
			(layer "F.Fab")
		)
		(fp_line
			(start -0.67945 -0.305054)
			(end -0.12065 -0.305054)
			(stroke
				(width 0.1)
				(type default)
			)
			(layer "F.Fab")
		)
		(fp_line
			(start 0.67945 -0.3048)
			(end 0.67945 0.3048)
			(stroke
				(width 0.1)
				(type default)
			)
			(layer "F.Fab")
		)
		(fp_line
			(start 0.12065 -0.3048)
			(end 0.67945 -0.3048)
			(stroke
				(width 0.1)
				(type default)
			)
			(layer "F.Fab")
		)
		(fp_line
			(start 0.12065 -0.2794)
			(end 0.12065 -0.3048)
			(stroke
				(width 0.1)
				(type default)
			)
			(layer "F.Fab")
		)
		(fp_line
			(start -0.12065 -0.2794)
			(end 0.12065 -0.2794)
			(stroke
				(width 0.1)
				(type default)
			)
			(layer "F.Fab")
		)
		(fp_line
			(start 0.120396 0.2794)
			(end -0.12065 0.2794)
			(stroke
				(width 0.1)
				(type default)
			)
			(layer "F.Fab")
		)
		(fp_line
			(start -0.12065 0.2794)
			(end -0.12065 0.3048)
			(stroke
				(width 0.1)
				(type default)
			)
			(layer "F.Fab")
		)
		(fp_line
			(start 0.67945 0.3048)
			(end 0.120396 0.3048)
			(stroke
				(width 0.1)
				(type default)
			)
			(layer "F.Fab")
		)
		(fp_line
			(start 0.120396 0.3048)
			(end 0.120396 0.2794)
			(stroke
				(width 0.1)
				(type default)
			)
			(layer "F.Fab")
		)
		(fp_line
			(start -0.12065 0.3048)
			(end -0.67945 0.3048)
			(stroke
				(width 0.1)
				(type default)
			)
			(layer "F.Fab")
		)
		(fp_line
			(start -0.67945 0.3048)
			(end -0.67945 -0.305054)
			(stroke
				(width 0.1)
				(type default)
			)
			(layer "F.Fab")
		)
		(pad "1" smd circle
			(at -0.40005 0 90)
			(size 0 0)
			(layers "F.Cu" "F.Mask" "F.Paste")
			(net "FM_SMM_CRASHDUMP")
		)
		(pad "2" smd circle
			(at 0.40005 0 90)
			(size 0 0)
			(layers "F.Cu" "F.Mask" "F.Paste")
			(net "FM_SMM_CRASHDUMP_R")
		)
	)
	(footprint ""
		(layer "F.Cu")
		(at 152.848818 -34.647632)
		(property "Reference" "R1180"
			(at 0 0 0)
			(layer "F.SilkS")
			(hide yes)
			(effects
				(font
					(size 1.27 1.27)
				)
			)
		)
		(property "Value" ""
			(at 0 0 0)
			(layer "F.Fab")
			(effects
				(font
					(size 1.27 1.27)
				)
			)
		)
		(duplicate_pad_numbers_are_jumpers no)
		(fp_line
			(start -0.7874 -0.4064)
			(end 0.7874 -0.4064)
			(stroke
				(width 0.1524)
				(type default)
			)
			(layer "F.SilkS")
		)
		(fp_line
			(start -0.7874 0.4064)
			(end -0.7874 -0.4064)
			(stroke
				(width 0.1524)
				(type default)
			)
			(layer "F.SilkS")
		)
		(fp_line
			(start 0.7874 -0.4064)
			(end 0.7874 0.4064)
			(stroke
				(width 0.1524)
				(type default)
			)
			(layer "F.SilkS")
		)
		(fp_line
			(start 0.7874 0.4064)
			(end -0.7874 0.4064)
			(stroke
				(width 0.1524)
				(type default)
			)
			(layer "F.SilkS")
		)
		(fp_line
			(start -0.67945 -0.305054)
			(end -0.12065 -0.305054)
			(stroke
				(width 0.1)
				(type default)
			)
			(layer "F.Fab")
		)
		(fp_line
			(start -0.67945 0.3048)
			(end -0.67945 -0.305054)
			(stroke
				(width 0.1)
				(type default)
			)
			(layer "F.Fab")
		)
		(fp_line
			(start -0.12065 -0.305054)
			(end -0.12065 -0.2794)
			(stroke
				(width 0.1)
				(type default)
			)
			(layer "F.Fab")
		)
		(fp_line
			(start -0.12065 -0.2794)
			(end 0.12065 -0.2794)
			(stroke
				(width 0.1)
				(type default)
			)
			(layer "F.Fab")
		)
		(fp_line
			(start -0.12065 0.2794)
			(end -0.12065 0.3048)
			(stroke
				(width 0.1)
				(type default)
			)
			(layer "F.Fab")
		)
		(fp_line
			(start -0.12065 0.3048)
			(end -0.67945 0.3048)
			(stroke
				(width 0.1)
				(type default)
			)
			(layer "F.Fab")
		)
		(fp_line
			(start 0.120396 0.2794)
			(end -0.12065 0.2794)
			(stroke
				(width 0.1)
				(type default)
			)
			(layer "F.Fab")
		)
		(fp_line
			(start 0.120396 0.3048)
			(end 0.120396 0.2794)
			(stroke
				(width 0.1)
				(type default)
			)
			(layer "F.Fab")
		)
		(fp_line
			(start 0.12065 -0.3048)
			(end 0.67945 -0.3048)
			(stroke
				(width 0.1)
				(type default)
			)
			(layer "F.Fab")
		)
		(fp_line
			(start 0.12065 -0.2794)
			(end 0.12065 -0.3048)
			(stroke
				(width 0.1)
				(type default)
			)
			(layer "F.Fab")
		)
		(fp_line
			(start 0.67945 -0.3048)
			(end 0.67945 0.3048)
			(stroke
				(width 0.1)
				(type default)
			)
			(layer "F.Fab")
		)
		(fp_line
			(start 0.67945 0.3048)
			(end 0.120396 0.3048)
			(stroke
				(width 0.1)
				(type default)
			)
			(layer "F.Fab")
		)
		(pad "1" smd circle
			(at -0.40005 0)
			(size 0 0)
			(layers "F.Cu" "F.Mask" "F.Paste")
			(net "HP_LVC3_OCP_V3_2_R_EN")
		)
		(pad "2" smd circle
			(at 0.40005 0)
			(size 0 0)
			(layers "F.Cu" "F.Mask" "F.Paste")
			(net "HP_LVC3_OCP_V3_2_P12V_PWRGD")
		)
	)
)
